(kicad_pcb
	(version 20260206)
	(generator "pcbnew")
	(generator_version "10.0")
	(general
		(thickness 1.6)
		(legacy_teardrops no)
	)
	(paper "A4")
	(title_block
		(title "04192023_DAF0TMB3IC0_F0TG_MB_C_brd_V02_OCP.brd")
		(comment 1 "Grand Teton / footprints 3147-3153 of 8354")
	)
	(layers
		(0 "F.Cu" signal "TOP")
		(4 "In1.Cu" signal "GND")
		(6 "In2.Cu" signal "IN1")
		(8 "In3.Cu" signal "GND1")
		(10 "In4.Cu" signal "IN2")
		(12 "In5.Cu" signal "GND2")
		(14 "In6.Cu" signal "IN3")
		(16 "In7.Cu" signal "GND3")
		(18 "In8.Cu" signal "VCC")
		(20 "In9.Cu" signal "VCC1")
		(22 "In10.Cu" signal "GND4")
		(24 "In11.Cu" signal "IN4")
		(26 "In12.Cu" signal "GND5")
		(28 "In13.Cu" signal "IN5")
		(30 "In14.Cu" signal "GND6")
		(32 "In15.Cu" signal "IN6")
		(34 "In16.Cu" signal "GND7")
		(2 "B.Cu" signal "BOTTOM")
		(9 "F.Adhes" user "F.Adhesive")
		(11 "B.Adhes" user "B.Adhesive")
		(13 "F.Paste" user "Package Geometry/Pastemask Top")
		(15 "B.Paste" user "Package Geometry/Pastemask Bottom")
		(5 "F.SilkS" user "Ref Des/Silkscreen Top")
		(7 "B.SilkS" user "Ref Des/Silkscreen Bottom")
		(1 "F.Mask" user "Board Geometry/Soldermask Top")
		(3 "B.Mask" user "Board Geometry/Soldermask Bottom")
		(17 "Dwgs.User" user "User.Drawings")
		(19 "Cmts.User" user "User.Comments")
		(21 "Eco1.User" user "User.Eco1")
		(23 "Eco2.User" user "User.Eco2")
		(25 "Edge.Cuts" user "Board Geometry/Outline")
		(27 "Margin" user)
		(31 "F.CrtYd" user "Package Geometry/Place Bound Top")
		(29 "B.CrtYd" user "Package Geometry/Place Bound Bottom")
		(35 "F.Fab" user "Ref Des/Assembly Top")
		(33 "B.Fab" user "Ref Des/Assembly Bottom")
	)
	(footprint ""
		(layer "F.Cu")
		(at 186.387994 -133.537198 -90)
		(property "Reference" "R1362"
			(at 0 0 270)
			(layer "F.SilkS")
			(hide yes)
			(effects
				(font
					(size 1.27 1.27)
				)
			)
		)
		(property "Value" ""
			(at 0 0 270)
			(layer "F.Fab")
			(effects
				(font
					(size 1.27 1.27)
				)
			)
		)
		(duplicate_pad_numbers_are_jumpers no)
		(fp_line
			(start -0.7874 0.4064)
			(end -0.7874 -0.4064)
			(stroke
				(width 0.1524)
				(type default)
			)
			(layer "F.SilkS")
		)
		(fp_line
			(start 0.7874 0.4064)
			(end -0.7874 0.4064)
			(stroke
				(width 0.1524)
				(type default)
			)
			(layer "F.SilkS")
		)
		(fp_line
			(start -0.7874 -0.4064)
			(end 0.7874 -0.4064)
			(stroke
				(width 0.1524)
				(type default)
			)
			(layer "F.SilkS")
		)
		(fp_line
			(start 0.7874 -0.4064)
			(end 0.7874 0.4064)
			(stroke
				(width 0.1524)
				(type default)
			)
			(layer "F.SilkS")
		)
		(fp_line
			(start -0.67945 0.3048)
			(end -0.67945 -0.305054)
			(stroke
				(width 0.1)
				(type default)
			)
			(layer "F.Fab")
		)
		(fp_line
			(start -0.12065 0.3048)
			(end -0.67945 0.3048)
			(stroke
				(width 0.1)
				(type default)
			)
			(layer "F.Fab")
		)
		(fp_line
			(start 0.120396 0.3048)
			(end 0.120396 0.2794)
			(stroke
				(width 0.1)
				(type default)
			)
			(layer "F.Fab")
		)
		(fp_line
			(start 0.67945 0.3048)
			(end 0.120396 0.3048)
			(stroke
				(width 0.1)
				(type default)
			)
			(layer "F.Fab")
		)
		(fp_line
			(start -0.12065 0.2794)
			(end -0.12065 0.3048)
			(stroke
				(width 0.1)
				(type default)
			)
			(layer "F.Fab")
		)
		(fp_line
			(start 0.120396 0.2794)
			(end -0.12065 0.2794)
			(stroke
				(width 0.1)
				(type default)
			)
			(layer "F.Fab")
		)
		(fp_line
			(start -0.12065 -0.2794)
			(end 0.12065 -0.2794)
			(stroke
				(width 0.1)
				(type default)
			)
			(layer "F.Fab")
		)
		(fp_line
			(start 0.12065 -0.2794)
			(end 0.12065 -0.3048)
			(stroke
				(width 0.1)
				(type default)
			)
			(layer "F.Fab")
		)
		(fp_line
			(start 0.12065 -0.3048)
			(end 0.67945 -0.3048)
			(stroke
				(width 0.1)
				(type default)
			)
			(layer "F.Fab")
		)
		(fp_line
			(start 0.67945 -0.3048)
			(end 0.67945 0.3048)
			(stroke
				(width 0.1)
				(type default)
			)
			(layer "F.Fab")
		)
		(fp_line
			(start -0.67945 -0.305054)
			(end -0.12065 -0.305054)
			(stroke
				(width 0.1)
				(type default)
			)
			(layer "F.Fab")
		)
		(fp_line
			(start -0.12065 -0.305054)
			(end -0.12065 -0.2794)
			(stroke
				(width 0.1)
				(type default)
			)
			(layer "F.Fab")
		)
		(pad "1" smd circle
			(at -0.40005 0 270)
			(size 0 0)
			(layers "F.Cu" "F.Mask" "F.Paste")
			(net "PWRGD_P3V3_R1")
		)
		(pad "2" smd circle
			(at 0.40005 0 270)
			(size 0 0)
			(layers "F.Cu" "F.Mask" "F.Paste")
			(net "PWRGD_P3V3_R2")
		)
	)
	(footprint ""
		(layer "F.Cu")
		(at 48.095154 -375.49963 -90)
		(property "Reference" "C829"
			(at 0 0 270)
			(layer "F.SilkS")
			(hide yes)
			(effects
				(font
					(size 1.27 1.27)
				)
			)
		)
		(property "Value" ""
			(at 0 0 270)
			(layer "F.Fab")
			(effects
				(font
					(size 1.27 1.27)
				)
			)
		)
		(duplicate_pad_numbers_are_jumpers no)
		(fp_line
			(start -0.299974 0.150114)
			(end -0.299974 -0.150114)
			(stroke
				(width 0.1)
				(type default)
			)
			(layer "F.Fab")
		)
		(fp_line
			(start 0.299974 0.150114)
			(end -0.299974 0.150114)
			(stroke
				(width 0.1)
				(type default)
			)
			(layer "F.Fab")
		)
		(fp_line
			(start -0.299974 -0.150114)
			(end 0.299974 -0.150114)
			(stroke
				(width 0.1)
				(type default)
			)
			(layer "F.Fab")
		)
		(fp_line
			(start 0.299974 -0.150114)
			(end 0.299974 0.150114)
			(stroke
				(width 0.1)
				(type default)
			)
			(layer "F.Fab")
		)
		(pad "1" smd rect
			(at -0.2667 0 270)
			(size 0.3048 0.381)
			(layers "F.Cu" "F.Mask" "F.Paste")
			(net "P5E_CPU1_P0_TX_C_DP<4>")
		)
		(pad "2" smd rect
			(at 0.2667 0 270)
			(size 0.3048 0.381)
			(layers "F.Cu" "F.Mask" "F.Paste")
			(net "P5E_CPU1_P0_TX_DP<4>")
		)
	)
	(footprint ""
		(layer "F.Cu")
		(at 184.801256 -96.103948 90)
		(property "Reference" "R6054"
			(at 0 0 90)
			(layer "F.SilkS")
			(hide yes)
			(effects
				(font
					(size 1.27 1.27)
				)
			)
		)
		(property "Value" ""
			(at 0 0 90)
			(layer "F.Fab")
			(effects
				(font
					(size 1.27 1.27)
				)
			)
		)
		(duplicate_pad_numbers_are_jumpers no)
		(fp_line
			(start 0.7874 -0.4064)
			(end 0.7874 0.4064)
			(stroke
				(width 0.1524)
				(type default)
			)
			(layer "F.SilkS")
		)
		(fp_line
			(start -0.7874 -0.4064)
			(end 0.7874 -0.4064)
			(stroke
				(width 0.1524)
				(type default)
			)
			(layer "F.SilkS")
		)
		(fp_line
			(start 0.7874 0.4064)
			(end -0.7874 0.4064)
			(stroke
				(width 0.1524)
				(type default)
			)
			(layer "F.SilkS")
		)
		(fp_line
			(start -0.7874 0.4064)
			(end -0.7874 -0.4064)
			(stroke
				(width 0.1524)
				(type default)
			)
			(layer "F.SilkS")
		)
		(fp_line
			(start -0.12065 -0.305054)
			(end -0.12065 -0.2794)
			(stroke
				(width 0.1)
				(type default)
			)
			(layer "F.Fab")
		)
		(fp_line
			(start -0.67945 -0.305054)
			(end -0.12065 -0.305054)
			(stroke
				(width 0.1)
				(type default)
			)
			(layer "F.Fab")
		)
		(fp_line
			(start 0.67945 -0.3048)
			(end 0.67945 0.3048)
			(stroke
				(width 0.1)
				(type default)
			)
			(layer "F.Fab")
		)
		(fp_line
			(start 0.12065 -0.3048)
			(end 0.67945 -0.3048)
			(stroke
				(width 0.1)
				(type default)
			)
			(layer "F.Fab")
		)
		(fp_line
			(start 0.12065 -0.2794)
			(end 0.12065 -0.3048)
			(stroke
				(width 0.1)
				(type default)
			)
			(layer "F.Fab")
		)
		(fp_line
			(start -0.12065 -0.2794)
			(end 0.12065 -0.2794)
			(stroke
				(width 0.1)
				(type default)
			)
			(layer "F.Fab")
		)
		(fp_line
			(start 0.120396 0.2794)
			(end -0.12065 0.2794)
			(stroke
				(width 0.1)
				(type default)
			)
			(layer "F.Fab")
		)
		(fp_line
			(start -0.12065 0.2794)
			(end -0.12065 0.3048)
			(stroke
				(width 0.1)
				(type default)
			)
			(layer "F.Fab")
		)
		(fp_line
			(start 0.67945 0.3048)
			(end 0.120396 0.3048)
			(stroke
				(width 0.1)
				(type default)
			)
			(layer "F.Fab")
		)
		(fp_line
			(start 0.120396 0.3048)
			(end 0.120396 0.2794)
			(stroke
				(width 0.1)
				(type default)
			)
			(layer "F.Fab")
		)
		(fp_line
			(start -0.12065 0.3048)
			(end -0.67945 0.3048)
			(stroke
				(width 0.1)
				(type default)
			)
			(layer "F.Fab")
		)
		(fp_line
			(start -0.67945 0.3048)
			(end -0.67945 -0.305054)
			(stroke
				(width 0.1)
				(type default)
			)
			(layer "F.Fab")
		)
		(pad "1" smd circle
			(at -0.40005 0 90)
			(size 0 0)
			(layers "F.Cu" "F.Mask" "F.Paste")
			(net "FM_OCP_SFF_PWR_GOOD")
		)
		(pad "2" smd circle
			(at 0.40005 0 90)
			(size 0 0)
			(layers "F.Cu" "F.Mask" "F.Paste")
			(net "PWRGD_OCP_SFF_PWR_GOOD")
		)
	)
	(footprint ""
		(layer "F.Cu")
		(at 369.511326 -43.235118 -90)
		(property "Reference" "R815"
			(at 0 0 270)
			(layer "F.SilkS")
			(hide yes)
			(effects
				(font
					(size 1.27 1.27)
				)
			)
		)
		(property "Value" ""
			(at 0 0 270)
			(layer "F.Fab")
			(effects
				(font
					(size 1.27 1.27)
				)
			)
		)
		(duplicate_pad_numbers_are_jumpers no)
		(fp_line
			(start -0.7874 0.4064)
			(end -0.7874 -0.4064)
			(stroke
				(width 0.1524)
				(type default)
			)
			(layer "F.SilkS")
		)
		(fp_line
			(start 0.7874 0.4064)
			(end -0.7874 0.4064)
			(stroke
				(width 0.1524)
				(type default)
			)
			(layer "F.SilkS")
		)
		(fp_line
			(start -0.7874 -0.4064)
			(end 0.7874 -0.4064)
			(stroke
				(width 0.1524)
				(type default)
			)
			(layer "F.SilkS")
		)
		(fp_line
			(start 0.7874 -0.4064)
			(end 0.7874 0.4064)
			(stroke
				(width 0.1524)
				(type default)
			)
			(layer "F.SilkS")
		)
		(fp_line
			(start -0.67945 0.3048)
			(end -0.67945 -0.305054)
			(stroke
				(width 0.1)
				(type default)
			)
			(layer "F.Fab")
		)
		(fp_line
			(start -0.12065 0.3048)
			(end -0.67945 0.3048)
			(stroke
				(width 0.1)
				(type default)
			)
			(layer "F.Fab")
		)
		(fp_line
			(start 0.120396 0.3048)
			(end 0.120396 0.2794)
			(stroke
				(width 0.1)
				(type default)
			)
			(layer "F.Fab")
		)
		(fp_line
			(start 0.67945 0.3048)
			(end 0.120396 0.3048)
			(stroke
				(width 0.1)
				(type default)
			)
			(layer "F.Fab")
		)
		(fp_line
			(start -0.12065 0.2794)
			(end -0.12065 0.3048)
			(stroke
				(width 0.1)
				(type default)
			)
			(layer "F.Fab")
		)
		(fp_line
			(start 0.120396 0.2794)
			(end -0.12065 0.2794)
			(stroke
				(width 0.1)
				(type default)
			)
			(layer "F.Fab")
		)
		(fp_line
			(start -0.12065 -0.2794)
			(end 0.12065 -0.2794)
			(stroke
				(width 0.1)
				(type default)
			)
			(layer "F.Fab")
		)
		(fp_line
			(start 0.12065 -0.2794)
			(end 0.12065 -0.3048)
			(stroke
				(width 0.1)
				(type default)
			)
			(layer "F.Fab")
		)
		(fp_line
			(start 0.12065 -0.3048)
			(end 0.67945 -0.3048)
			(stroke
				(width 0.1)
				(type default)
			)
			(layer "F.Fab")
		)
		(fp_line
			(start 0.67945 -0.3048)
			(end 0.67945 0.3048)
			(stroke
				(width 0.1)
				(type default)
			)
			(layer "F.Fab")
		)
		(fp_line
			(start -0.67945 -0.305054)
			(end -0.12065 -0.305054)
			(stroke
				(width 0.1)
				(type default)
			)
			(layer "F.Fab")
		)
		(fp_line
			(start -0.12065 -0.305054)
			(end -0.12065 -0.2794)
			(stroke
				(width 0.1)
				(type default)
			)
			(layer "F.Fab")
		)
		(pad "1" smd circle
			(at -0.40005 0 270)
			(size 0 0)
			(layers "F.Cu" "F.Mask" "F.Paste")
			(net "PVDD18_S5_P0")
		)
		(pad "2" smd circle
			(at 0.40005 0 270)
			(size 0 0)
			(layers "F.Cu" "F.Mask" "F.Paste")
			(net "UART_CPU0_SCM_UART1_TX")
		)
	)
	(footprint ""
		(layer "F.Cu")
		(at 325.740776 -388.767828)
		(property "Reference" "C902"
			(at 0 0 0)
			(layer "F.SilkS")
			(hide yes)
			(effects
				(font
					(size 1.27 1.27)
				)
			)
		)
		(property "Value" ""
			(at 0 0 0)
			(layer "F.Fab")
			(effects
				(font
					(size 1.27 1.27)
				)
			)
		)
		(duplicate_pad_numbers_are_jumpers no)
		(fp_line
			(start -0.299974 -0.150114)
			(end 0.299974 -0.150114)
			(stroke
				(width 0.1)
				(type default)
			)
			(layer "F.Fab")
		)
		(fp_line
			(start -0.299974 0.150114)
			(end -0.299974 -0.150114)
			(stroke
				(width 0.1)
				(type default)
			)
			(layer "F.Fab")
		)
		(fp_line
			(start 0.299974 -0.150114)
			(end 0.299974 0.150114)
			(stroke
				(width 0.1)
				(type default)
			)
			(layer "F.Fab")
		)
		(fp_line
			(start 0.299974 0.150114)
			(end -0.299974 0.150114)
			(stroke
				(width 0.1)
				(type default)
			)
			(layer "F.Fab")
		)
		(pad "1" smd rect
			(at -0.2667 0)
			(size 0.3048 0.381)
			(layers "F.Cu" "F.Mask" "F.Paste")
			(net "P5E_CPU0_P0_TX_C_DN<15>")
		)
		(pad "2" smd rect
			(at 0.2667 0)
			(size 0.3048 0.381)
			(layers "F.Cu" "F.Mask" "F.Paste")
			(net "P5E_CPU0_P0_TX_DN<15>")
		)
	)
	(footprint ""
		(layer "F.Cu")
		(at 240.596674 -155.9941)
		(property "Reference" "R1651"
			(at 0 0 0)
			(layer "F.SilkS")
			(hide yes)
			(effects
				(font
					(size 1.27 1.27)
				)
			)
		)
		(property "Value" ""
			(at 0 0 0)
			(layer "F.Fab")
			(effects
				(font
					(size 1.27 1.27)
				)
			)
		)
		(duplicate_pad_numbers_are_jumpers no)
		(fp_line
			(start -0.7874 -0.4064)
			(end 0.7874 -0.4064)
			(stroke
				(width 0.1524)
				(type default)
			)
			(layer "F.SilkS")
		)
		(fp_line
			(start -0.7874 0.4064)
			(end -0.7874 -0.4064)
			(stroke
				(width 0.1524)
				(type default)
			)
			(layer "F.SilkS")
		)
		(fp_line
			(start 0.7874 -0.4064)
			(end 0.7874 0.4064)
			(stroke
				(width 0.1524)
				(type default)
			)
			(layer "F.SilkS")
		)
		(fp_line
			(start 0.7874 0.4064)
			(end -0.7874 0.4064)
			(stroke
				(width 0.1524)
				(type default)
			)
			(layer "F.SilkS")
		)
		(fp_line
			(start -0.67945 -0.305054)
			(end -0.12065 -0.305054)
			(stroke
				(width 0.1)
				(type default)
			)
			(layer "F.Fab")
		)
		(fp_line
			(start -0.67945 0.3048)
			(end -0.67945 -0.305054)
			(stroke
				(width 0.1)
				(type default)
			)
			(layer "F.Fab")
		)
		(fp_line
			(start -0.12065 -0.305054)
			(end -0.12065 -0.2794)
			(stroke
				(width 0.1)
				(type default)
			)
			(layer "F.Fab")
		)
		(fp_line
			(start -0.12065 -0.2794)
			(end 0.12065 -0.2794)
			(stroke
				(width 0.1)
				(type default)
			)
			(layer "F.Fab")
		)
		(fp_line
			(start -0.12065 0.2794)
			(end -0.12065 0.3048)
			(stroke
				(width 0.1)
				(type default)
			)
			(layer "F.Fab")
		)
		(fp_line
			(start -0.12065 0.3048)
			(end -0.67945 0.3048)
			(stroke
				(width 0.1)
				(type default)
			)
			(layer "F.Fab")
		)
		(fp_line
			(start 0.120396 0.2794)
			(end -0.12065 0.2794)
			(stroke
				(width 0.1)
				(type default)
			)
			(layer "F.Fab")
		)
		(fp_line
			(start 0.120396 0.3048)
			(end 0.120396 0.2794)
			(stroke
				(width 0.1)
				(type default)
			)
			(layer "F.Fab")
		)
		(fp_line
			(start 0.12065 -0.3048)
			(end 0.67945 -0.3048)
			(stroke
				(width 0.1)
				(type default)
			)
			(layer "F.Fab")
		)
		(fp_line
			(start 0.12065 -0.2794)
			(end 0.12065 -0.3048)
			(stroke
				(width 0.1)
				(type default)
			)
			(layer "F.Fab")
		)
		(fp_line
			(start 0.67945 -0.3048)
			(end 0.67945 0.3048)
			(stroke
				(width 0.1)
				(type default)
			)
			(layer "F.Fab")
		)
		(fp_line
			(start 0.67945 0.3048)
			(end 0.120396 0.3048)
			(stroke
				(width 0.1)
				(type default)
			)
			(layer "F.Fab")
		)
		(pad "1" smd circle
			(at -0.40005 0)
			(size 0 0)
			(layers "F.Cu" "F.Mask" "F.Paste")
			(net "JTAG_CPU1_R_TDI")
		)
		(pad "2" smd circle
			(at 0.40005 0)
			(size 0 0)
			(layers "F.Cu" "F.Mask" "F.Paste")
			(net "JTAG_CPU1_TDI")
		)
	)
	(footprint ""
		(layer "F.Cu")
		(at 95.38335 -59.80557 180)
		(property "Reference" "PC2147"
			(at 0 0 180)
			(layer "F.SilkS")
			(hide yes)
			(effects
				(font
					(size 1.27 1.27)
				)
			)
		)
		(property "Value" ""
			(at 0 0 180)
			(layer "F.Fab")
			(effects
				(font
					(size 1.27 1.27)
				)
			)
		)
		(duplicate_pad_numbers_are_jumpers no)
		(fp_line
			(start 0.7874 0.4064)
			(end -0.7874 0.4064)
			(stroke
				(width 0.1524)
				(type default)
			)
			(layer "F.SilkS")
		)
		(fp_line
			(start 0.7874 -0.4064)
			(end 0.7874 0.4064)
			(stroke
				(width 0.1524)
				(type default)
			)
			(layer "F.SilkS")
		)
		(fp_line
			(start -0.7874 0.4064)
			(end -0.7874 -0.4064)
			(stroke
				(width 0.1524)
				(type default)
			)
			(layer "F.SilkS")
		)
		(fp_line
			(start -0.7874 -0.4064)
			(end 0.7874 -0.4064)
			(stroke
				(width 0.1524)
				(type default)
			)
			(layer "F.SilkS")
		)
		(fp_line
			(start 0.67945 0.3048)
			(end 0.120396 0.3048)
			(stroke
				(width 0.1)
				(type default)
			)
			(layer "F.Fab")
		)
		(fp_line
			(start 0.67945 -0.3048)
			(end 0.67945 0.3048)
			(stroke
				(width 0.1)
				(type default)
			)
			(layer "F.Fab")
		)
		(fp_line
			(start 0.12065 -0.2794)
			(end 0.12065 -0.3048)
			(stroke
				(width 0.1)
				(type default)
			)
			(layer "F.Fab")
		)
		(fp_line
			(start 0.12065 -0.3048)
			(end 0.67945 -0.3048)
			(stroke
				(width 0.1)
				(type default)
			)
			(layer "F.Fab")
		)
		(fp_line
			(start 0.120396 0.3048)
			(end 0.120396 0.2794)
			(stroke
				(width 0.1)
				(type default)
			)
			(layer "F.Fab")
		)
		(fp_line
			(start 0.120396 0.2794)
			(end -0.12065 0.2794)
			(stroke
				(width 0.1)
				(type default)
			)
			(layer "F.Fab")
		)
		(fp_line
			(start -0.12065 0.3048)
			(end -0.67945 0.3048)
			(stroke
				(width 0.1)
				(type default)
			)
			(layer "F.Fab")
		)
		(fp_line
			(start -0.12065 0.2794)
			(end -0.12065 0.3048)
			(stroke
				(width 0.1)
				(type default)
			)
			(layer "F.Fab")
		)
		(fp_line
			(start -0.12065 -0.2794)
			(end 0.12065 -0.2794)
			(stroke
				(width 0.1)
				(type default)
			)
			(layer "F.Fab")
		)
		(fp_line
			(start -0.12065 -0.305054)
			(end -0.12065 -0.2794)
			(stroke
				(width 0.1)
				(type default)
			)
			(layer "F.Fab")
		)
		(fp_line
			(start -0.67945 0.3048)
			(end -0.67945 -0.305054)
			(stroke
				(width 0.1)
				(type default)
			)
			(layer "F.Fab")
		)
		(fp_line
			(start -0.67945 -0.305054)
			(end -0.12065 -0.305054)
			(stroke
				(width 0.1)
				(type default)
			)
			(layer "F.Fab")
		)
		(pad "1" smd circle
			(at -0.40005 0 180)
			(size 0 0)
			(layers "F.Cu" "F.Mask" "F.Paste")
			(net "GND")
		)
		(pad "2" smd circle
			(at 0.40005 0 180)
			(size 0 0)
			(layers "F.Cu" "F.Mask" "F.Paste")
			(net "P3V3_OCP_REG_2")
		)
	)
)
